(kicad_pcb
	(version 20260206)
	(generator "pcbnew")
	(generator_version "10.0")
	(general
		(thickness 1.6)
		(legacy_teardrops no)
	)
	(paper "A4")
	(title_block
		(title "01162023_DA0F0TEBIF0_F0T_Expander_BD_F_brd_V02_OCP.brd")
		(comment 1 "Grand Teton / footprints 7360-7368 of 9728")
	)
	(layers
		(0 "F.Cu" signal "TOP")
		(4 "In1.Cu" signal "GND")
		(6 "In2.Cu" signal "VCC")
		(8 "In3.Cu" signal "VCC1")
		(10 "In4.Cu" signal "GND1")
		(12 "In5.Cu" signal "IN1")
		(14 "In6.Cu" signal "GND2")
		(16 "In7.Cu" signal "IN2")
		(18 "In8.Cu" signal "GND3")
		(20 "In9.Cu" signal "IN3")
		(22 "In10.Cu" signal "GND4")
		(24 "In11.Cu" signal "IN4")
		(26 "In12.Cu" signal "GND5")
		(28 "In13.Cu" signal "IN5")
		(30 "In14.Cu" signal "GND6")
		(32 "In15.Cu" signal "IN6")
		(34 "In16.Cu" signal "GND7")
		(2 "B.Cu" signal "BOTTOM")
		(9 "F.Adhes" user "F.Adhesive")
		(11 "B.Adhes" user "B.Adhesive")
		(13 "F.Paste" user "Package Geometry/Pastemask Top")
		(15 "B.Paste" user "Package Geometry/Pastemask Bottom")
		(5 "F.SilkS" user "Ref Des/Silkscreen Top")
		(7 "B.SilkS" user "Ref Des/Silkscreen Bottom")
		(1 "F.Mask" user "Board Geometry/Soldermask Top")
		(3 "B.Mask" user "Board Geometry/Soldermask Bottom")
		(17 "Dwgs.User" user "User.Drawings")
		(19 "Cmts.User" user "User.Comments")
		(21 "Eco1.User" user "User.Eco1")
		(23 "Eco2.User" user "User.Eco2")
		(25 "Edge.Cuts" user "Board Geometry/Outline")
		(27 "Margin" user)
		(31 "F.CrtYd" user "Package Geometry/Place Bound Top")
		(29 "B.CrtYd" user "Package Geometry/Place Bound Bottom")
		(35 "F.Fab" user "Ref Des/Assembly Top")
		(33 "B.Fab" user "Ref Des/Assembly Bottom")
	)
	(footprint ""
		(layer "B.Cu")
		(at 24.711406 -223.315276 180)
		(property "Reference" "C2755"
			(at 0 0 0)
			(layer "B.SilkS")
			(hide yes)
			(effects
				(font
					(size 1.27 1.27)
				)
				(justify mirror)
			)
		)
		(property "Value" ""
			(at 0 0 0)
			(layer "B.Fab")
			(effects
				(font
					(size 1.27 1.27)
				)
				(justify mirror)
			)
		)
		(duplicate_pad_numbers_are_jumpers no)
		(fp_line
			(start 0.7874 0.4064)
			(end 0.7874 -0.4064)
			(stroke
				(width 0.1524)
				(type default)
			)
			(layer "B.SilkS")
		)
		(fp_line
			(start 0.7874 -0.4064)
			(end -0.7874 -0.4064)
			(stroke
				(width 0.1524)
				(type default)
			)
			(layer "B.SilkS")
		)
		(fp_line
			(start -0.7874 0.4064)
			(end 0.7874 0.4064)
			(stroke
				(width 0.1524)
				(type default)
			)
			(layer "B.SilkS")
		)
		(fp_line
			(start -0.7874 -0.4064)
			(end -0.7874 0.4064)
			(stroke
				(width 0.1524)
				(type default)
			)
			(layer "B.SilkS")
		)
		(fp_line
			(start 0.67945 0.3048)
			(end 0.67945 -0.305054)
			(stroke
				(width 0.1)
				(type default)
			)
			(layer "B.Fab")
		)
		(fp_line
			(start 0.67945 -0.305054)
			(end 0.12065 -0.305054)
			(stroke
				(width 0.1)
				(type default)
			)
			(layer "B.Fab")
		)
		(fp_line
			(start 0.12065 0.3048)
			(end 0.67945 0.3048)
			(stroke
				(width 0.1)
				(type default)
			)
			(layer "B.Fab")
		)
		(fp_line
			(start 0.12065 0.2794)
			(end 0.12065 0.3048)
			(stroke
				(width 0.1)
				(type default)
			)
			(layer "B.Fab")
		)
		(fp_line
			(start 0.12065 -0.2794)
			(end -0.12065 -0.2794)
			(stroke
				(width 0.1)
				(type default)
			)
			(layer "B.Fab")
		)
		(fp_line
			(start 0.12065 -0.305054)
			(end 0.12065 -0.2794)
			(stroke
				(width 0.1)
				(type default)
			)
			(layer "B.Fab")
		)
		(fp_line
			(start -0.120396 0.3048)
			(end -0.120396 0.2794)
			(stroke
				(width 0.1)
				(type default)
			)
			(layer "B.Fab")
		)
		(fp_line
			(start -0.120396 0.2794)
			(end 0.12065 0.2794)
			(stroke
				(width 0.1)
				(type default)
			)
			(layer "B.Fab")
		)
		(fp_line
			(start -0.12065 -0.2794)
			(end -0.12065 -0.3048)
			(stroke
				(width 0.1)
				(type default)
			)
			(layer "B.Fab")
		)
		(fp_line
			(start -0.12065 -0.3048)
			(end -0.67945 -0.3048)
			(stroke
				(width 0.1)
				(type default)
			)
			(layer "B.Fab")
		)
		(fp_line
			(start -0.67945 0.3048)
			(end -0.120396 0.3048)
			(stroke
				(width 0.1)
				(type default)
			)
			(layer "B.Fab")
		)
		(fp_line
			(start -0.67945 -0.3048)
			(end -0.67945 0.3048)
			(stroke
				(width 0.1)
				(type default)
			)
			(layer "B.Fab")
		)
		(pad "1" smd circle
			(at 0.40005 0)
			(size 0 0)
			(layers "B.Cu" "B.Mask" "B.Paste")
			(net "GND")
		)
		(pad "2" smd circle
			(at -0.40005 0)
			(size 0 0)
			(layers "B.Cu" "B.Mask" "B.Paste")
			(net "P1V8_PEX")
		)
	)
	(footprint ""
		(layer "B.Cu")
		(at 238.538766 -214.3633)
		(property "Reference" "L146"
			(at 0 0 0)
			(layer "B.SilkS")
			(hide yes)
			(effects
				(font
					(size 1.27 1.27)
				)
				(justify mirror)
			)
		)
		(property "Value" ""
			(at 0 0 0)
			(layer "B.Fab")
			(effects
				(font
					(size 1.27 1.27)
				)
				(justify mirror)
			)
		)
		(duplicate_pad_numbers_are_jumpers no)
		(fp_line
			(start -1.27 0.5842)
			(end -1.27 -0.5842)
			(stroke
				(width 0.1524)
				(type default)
			)
			(layer "B.SilkS")
		)
		(fp_line
			(start -1.27 0.5842)
			(end 1.27 0.5842)
			(stroke
				(width 0.1524)
				(type default)
			)
			(layer "B.SilkS")
		)
		(fp_line
			(start 1.27 -0.5842)
			(end -1.27 -0.5842)
			(stroke
				(width 0.1524)
				(type default)
			)
			(layer "B.SilkS")
		)
		(fp_line
			(start 1.27 -0.5588)
			(end 1.27 -0.5842)
			(stroke
				(width 0.1524)
				(type default)
			)
			(layer "B.SilkS")
		)
		(fp_line
			(start 1.27 0.5842)
			(end 1.27 -0.5842)
			(stroke
				(width 0.1524)
				(type default)
			)
			(layer "B.SilkS")
		)
		(fp_line
			(start -1.1938 -0.406654)
			(end -1.1938 0.4064)
			(stroke
				(width 0.1)
				(type default)
			)
			(layer "B.Fab")
		)
		(fp_line
			(start -1.1938 0.4064)
			(end -0.9144 0.4064)
			(stroke
				(width 0.1)
				(type default)
			)
			(layer "B.Fab")
		)
		(fp_line
			(start -0.9144 -0.508)
			(end -0.9144 -0.406654)
			(stroke
				(width 0.1)
				(type default)
			)
			(layer "B.Fab")
		)
		(fp_line
			(start -0.9144 -0.406654)
			(end -1.1938 -0.406654)
			(stroke
				(width 0.1)
				(type default)
			)
			(layer "B.Fab")
		)
		(fp_line
			(start -0.9144 0.4064)
			(end -0.9144 0.508)
			(stroke
				(width 0.1)
				(type default)
			)
			(layer "B.Fab")
		)
		(fp_line
			(start -0.9144 0.508)
			(end 0.9144 0.508)
			(stroke
				(width 0.1)
				(type default)
			)
			(layer "B.Fab")
		)
		(fp_line
			(start 0.9144 -0.508)
			(end -0.9144 -0.508)
			(stroke
				(width 0.1)
				(type default)
			)
			(layer "B.Fab")
		)
		(fp_line
			(start 0.9144 -0.406654)
			(end 0.9144 -0.508)
			(stroke
				(width 0.1)
				(type default)
			)
			(layer "B.Fab")
		)
		(fp_line
			(start 0.9144 0.406654)
			(end 1.194308 0.406654)
			(stroke
				(width 0.1)
				(type default)
			)
			(layer "B.Fab")
		)
		(fp_line
			(start 0.9144 0.508)
			(end 0.9144 0.406654)
			(stroke
				(width 0.1)
				(type default)
			)
			(layer "B.Fab")
		)
		(fp_line
			(start 1.194308 -0.406654)
			(end 0.9144 -0.406654)
			(stroke
				(width 0.1)
				(type default)
			)
			(layer "B.Fab")
		)
		(fp_line
			(start 1.194308 0.406654)
			(end 1.194308 -0.406654)
			(stroke
				(width 0.1)
				(type default)
			)
			(layer "B.Fab")
		)
		(pad "1" smd rect
			(at 0.7366 0 270)
			(size 0.7112 0.8128)
			(layers "B.Cu" "B.Mask" "B.Paste")
			(net "P1V2_AUX")
		)
		(pad "2" smd rect
			(at -0.7366 0 270)
			(size 0.7112 0.8128)
			(layers "B.Cu" "B.Mask" "B.Paste")
			(net "P1V2_BIC_USB2AV12")
		)
	)
	(footprint ""
		(layer "B.Cu")
		(at 102.732586 -344.563954 90)
		(property "Reference" "R6367"
			(at 0 0 90)
			(layer "B.SilkS")
			(hide yes)
			(effects
				(font
					(size 1.27 1.27)
				)
				(justify mirror)
			)
		)
		(property "Value" ""
			(at 0 0 90)
			(layer "B.Fab")
			(effects
				(font
					(size 1.27 1.27)
				)
				(justify mirror)
			)
		)
		(duplicate_pad_numbers_are_jumpers no)
		(fp_line
			(start 0.7874 -0.4064)
			(end -0.7874 -0.4064)
			(stroke
				(width 0.1524)
				(type default)
			)
			(layer "B.SilkS")
		)
		(fp_line
			(start -0.7874 -0.4064)
			(end -0.7874 0.4064)
			(stroke
				(width 0.1524)
				(type default)
			)
			(layer "B.SilkS")
		)
		(fp_line
			(start 0.7874 0.4064)
			(end 0.7874 -0.4064)
			(stroke
				(width 0.1524)
				(type default)
			)
			(layer "B.SilkS")
		)
		(fp_line
			(start -0.7874 0.4064)
			(end 0.7874 0.4064)
			(stroke
				(width 0.1524)
				(type default)
			)
			(layer "B.SilkS")
		)
		(fp_line
			(start 0.67945 -0.305054)
			(end 0.12065 -0.305054)
			(stroke
				(width 0.1)
				(type default)
			)
			(layer "B.Fab")
		)
		(fp_line
			(start 0.12065 -0.305054)
			(end 0.12065 -0.2794)
			(stroke
				(width 0.1)
				(type default)
			)
			(layer "B.Fab")
		)
		(fp_line
			(start -0.12065 -0.3048)
			(end -0.67945 -0.3048)
			(stroke
				(width 0.1)
				(type default)
			)
			(layer "B.Fab")
		)
		(fp_line
			(start -0.67945 -0.3048)
			(end -0.67945 0.3048)
			(stroke
				(width 0.1)
				(type default)
			)
			(layer "B.Fab")
		)
		(fp_line
			(start 0.12065 -0.2794)
			(end -0.12065 -0.2794)
			(stroke
				(width 0.1)
				(type default)
			)
			(layer "B.Fab")
		)
		(fp_line
			(start -0.12065 -0.2794)
			(end -0.12065 -0.3048)
			(stroke
				(width 0.1)
				(type default)
			)
			(layer "B.Fab")
		)
		(fp_line
			(start 0.12065 0.2794)
			(end 0.12065 0.3048)
			(stroke
				(width 0.1)
				(type default)
			)
			(layer "B.Fab")
		)
		(fp_line
			(start -0.120396 0.2794)
			(end 0.12065 0.2794)
			(stroke
				(width 0.1)
				(type default)
			)
			(layer "B.Fab")
		)
		(fp_line
			(start 0.67945 0.3048)
			(end 0.67945 -0.305054)
			(stroke
				(width 0.1)
				(type default)
			)
			(layer "B.Fab")
		)
		(fp_line
			(start 0.12065 0.3048)
			(end 0.67945 0.3048)
			(stroke
				(width 0.1)
				(type default)
			)
			(layer "B.Fab")
		)
		(fp_line
			(start -0.120396 0.3048)
			(end -0.120396 0.2794)
			(stroke
				(width 0.1)
				(type default)
			)
			(layer "B.Fab")
		)
		(fp_line
			(start -0.67945 0.3048)
			(end -0.120396 0.3048)
			(stroke
				(width 0.1)
				(type default)
			)
			(layer "B.Fab")
		)
		(pad "1" smd circle
			(at 0.40005 0 270)
			(size 0 0)
			(layers "B.Cu" "B.Mask" "B.Paste")
			(net "CLK_100M_MB_1_R_DN")
		)
		(pad "2" smd circle
			(at -0.40005 0 270)
			(size 0 0)
			(layers "B.Cu" "B.Mask" "B.Paste")
			(net "CLK_100M_MB_1_DN")
		)
	)
	(footprint ""
		(layer "B.Cu")
		(at 73.400158 -109.251496)
		(property "Reference" "C864"
			(at 0 0 0)
			(layer "B.SilkS")
			(hide yes)
			(effects
				(font
					(size 1.27 1.27)
				)
				(justify mirror)
			)
		)
		(property "Value" ""
			(at 0 0 0)
			(layer "B.Fab")
			(effects
				(font
					(size 1.27 1.27)
				)
				(justify mirror)
			)
		)
		(duplicate_pad_numbers_are_jumpers no)
		(fp_line
			(start -0.299974 -0.150114)
			(end -0.299974 0.150114)
			(stroke
				(width 0.1)
				(type default)
			)
			(layer "B.Fab")
		)
		(fp_line
			(start -0.299974 0.150114)
			(end 0.299974 0.150114)
			(stroke
				(width 0.1)
				(type default)
			)
			(layer "B.Fab")
		)
		(fp_line
			(start 0.299974 -0.150114)
			(end -0.299974 -0.150114)
			(stroke
				(width 0.1)
				(type default)
			)
			(layer "B.Fab")
		)
		(fp_line
			(start 0.299974 0.150114)
			(end 0.299974 -0.150114)
			(stroke
				(width 0.1)
				(type default)
			)
			(layer "B.Fab")
		)
		(pad "1" smd rect
			(at 0.2667 0 180)
			(size 0.3048 0.381)
			(layers "B.Cu" "B.Mask" "B.Paste")
			(net "P12V_NIC1")
		)
		(pad "2" smd rect
			(at -0.2667 0 180)
			(size 0.3048 0.381)
			(layers "B.Cu" "B.Mask" "B.Paste")
			(net "GND")
		)
	)
	(footprint ""
		(layer "B.Cu")
		(at 360.919014 -308.677818 90)
		(property "Reference" "C4376"
			(at 0 0 90)
			(layer "B.SilkS")
			(hide yes)
			(effects
				(font
					(size 1.27 1.27)
				)
				(justify mirror)
			)
		)
		(property "Value" ""
			(at 0 0 90)
			(layer "B.Fab")
			(effects
				(font
					(size 1.27 1.27)
				)
				(justify mirror)
			)
		)
		(duplicate_pad_numbers_are_jumpers no)
		(fp_line
			(start 0.299974 -0.150114)
			(end -0.299974 -0.150114)
			(stroke
				(width 0.1)
				(type default)
			)
			(layer "B.Fab")
		)
		(fp_line
			(start -0.299974 -0.150114)
			(end -0.299974 0.150114)
			(stroke
				(width 0.1)
				(type default)
			)
			(layer "B.Fab")
		)
		(fp_line
			(start 0.299974 0.150114)
			(end 0.299974 -0.150114)
			(stroke
				(width 0.1)
				(type default)
			)
			(layer "B.Fab")
		)
		(fp_line
			(start -0.299974 0.150114)
			(end 0.299974 0.150114)
			(stroke
				(width 0.1)
				(type default)
			)
			(layer "B.Fab")
		)
		(pad "1" smd rect
			(at 0.2667 0 270)
			(size 0.3048 0.381)
			(layers "B.Cu" "B.Mask" "B.Paste")
			(net "P0V8_PEX3")
		)
		(pad "2" smd rect
			(at -0.2667 0 270)
			(size 0.3048 0.381)
			(layers "B.Cu" "B.Mask" "B.Paste")
			(net "GND")
		)
	)
	(footprint ""
		(layer "B.Cu")
		(at 102.25913 -308.42966 90)
		(property "Reference" "C4201"
			(at 0 0 90)
			(layer "B.SilkS")
			(hide yes)
			(effects
				(font
					(size 1.27 1.27)
				)
				(justify mirror)
			)
		)
		(property "Value" ""
			(at 0 0 90)
			(layer "B.Fab")
			(effects
				(font
					(size 1.27 1.27)
				)
				(justify mirror)
			)
		)
		(duplicate_pad_numbers_are_jumpers no)
		(fp_line
			(start 0.299974 -0.150114)
			(end -0.299974 -0.150114)
			(stroke
				(width 0.1)
				(type default)
			)
			(layer "B.Fab")
		)
		(fp_line
			(start -0.299974 -0.150114)
			(end -0.299974 0.150114)
			(stroke
				(width 0.1)
				(type default)
			)
			(layer "B.Fab")
		)
		(fp_line
			(start 0.299974 0.150114)
			(end 0.299974 -0.150114)
			(stroke
				(width 0.1)
				(type default)
			)
			(layer "B.Fab")
		)
		(fp_line
			(start -0.299974 0.150114)
			(end 0.299974 0.150114)
			(stroke
				(width 0.1)
				(type default)
			)
			(layer "B.Fab")
		)
		(pad "1" smd rect
			(at 0.2667 0 270)
			(size 0.3048 0.381)
			(layers "B.Cu" "B.Mask" "B.Paste")
			(net "P0V8_PEX0")
		)
		(pad "2" smd rect
			(at -0.2667 0 270)
			(size 0.3048 0.381)
			(layers "B.Cu" "B.Mask" "B.Paste")
			(net "GND")
		)
	)
	(footprint ""
		(layer "B.Cu")
		(at 179.07508 -305.399948 -90)
		(property "Reference" "C3139"
			(at 0 0 90)
			(layer "B.SilkS")
			(hide yes)
			(effects
				(font
					(size 1.27 1.27)
				)
				(justify mirror)
			)
		)
		(property "Value" ""
			(at 0 0 90)
			(layer "B.Fab")
			(effects
				(font
					(size 1.27 1.27)
				)
				(justify mirror)
			)
		)
		(duplicate_pad_numbers_are_jumpers no)
		(fp_line
			(start -0.299974 0.150114)
			(end 0.299974 0.150114)
			(stroke
				(width 0.1)
				(type default)
			)
			(layer "B.Fab")
		)
		(fp_line
			(start 0.299974 0.150114)
			(end 0.299974 -0.150114)
			(stroke
				(width 0.1)
				(type default)
			)
			(layer "B.Fab")
		)
		(fp_line
			(start -0.299974 -0.150114)
			(end -0.299974 0.150114)
			(stroke
				(width 0.1)
				(type default)
			)
			(layer "B.Fab")
		)
		(fp_line
			(start 0.299974 -0.150114)
			(end -0.299974 -0.150114)
			(stroke
				(width 0.1)
				(type default)
			)
			(layer "B.Fab")
		)
		(pad "1" smd rect
			(at 0.2667 0 90)
			(size 0.3048 0.381)
			(layers "B.Cu" "B.Mask" "B.Paste")
			(net "P1V25_SERDES_VDDPLL_PEX1")
		)
		(pad "2" smd rect
			(at -0.2667 0 90)
			(size 0.3048 0.381)
			(layers "B.Cu" "B.Mask" "B.Paste")
			(net "GND")
		)
	)
	(footprint ""
		(layer "B.Cu")
		(at 185.04154 -286.874966)
		(property "Reference" "C3171"
			(at 0 0 0)
			(layer "B.SilkS")
			(hide yes)
			(effects
				(font
					(size 1.27 1.27)
				)
				(justify mirror)
			)
		)
		(property "Value" ""
			(at 0 0 0)
			(layer "B.Fab")
			(effects
				(font
					(size 1.27 1.27)
				)
				(justify mirror)
			)
		)
		(duplicate_pad_numbers_are_jumpers no)
		(fp_line
			(start -0.299974 -0.150114)
			(end -0.299974 0.150114)
			(stroke
				(width 0.1)
				(type default)
			)
			(layer "B.Fab")
		)
		(fp_line
			(start -0.299974 0.150114)
			(end 0.299974 0.150114)
			(stroke
				(width 0.1)
				(type default)
			)
			(layer "B.Fab")
		)
		(fp_line
			(start 0.299974 -0.150114)
			(end -0.299974 -0.150114)
			(stroke
				(width 0.1)
				(type default)
			)
			(layer "B.Fab")
		)
		(fp_line
			(start 0.299974 0.150114)
			(end 0.299974 -0.150114)
			(stroke
				(width 0.1)
				(type default)
			)
			(layer "B.Fab")
		)
		(pad "1" smd rect
			(at 0.2667 0 180)
			(size 0.3048 0.381)
			(layers "B.Cu" "B.Mask" "B.Paste")
			(net "P1V8_VDDA_PEX1")
		)
		(pad "2" smd rect
			(at -0.2667 0 180)
			(size 0.3048 0.381)
			(layers "B.Cu" "B.Mask" "B.Paste")
			(net "GND")
		)
	)
	(footprint ""
		(layer "B.Cu")
		(at 189.500002 -111.791496)
		(property "Reference" "C892"
			(at 0 0 0)
			(layer "B.SilkS")
			(hide yes)
			(effects
				(font
					(size 1.27 1.27)
				)
				(justify mirror)
			)
		)
		(property "Value" ""
			(at 0 0 0)
			(layer "B.Fab")
			(effects
				(font
					(size 1.27 1.27)
				)
				(justify mirror)
			)
		)
		(duplicate_pad_numbers_are_jumpers no)
		(fp_line
			(start -0.299974 -0.150114)
			(end -0.299974 0.150114)
			(stroke
				(width 0.1)
				(type default)
			)
			(layer "B.Fab")
		)
		(fp_line
			(start -0.299974 0.150114)
			(end 0.299974 0.150114)
			(stroke
				(width 0.1)
				(type default)
			)
			(layer "B.Fab")
		)
		(fp_line
			(start 0.299974 -0.150114)
			(end -0.299974 -0.150114)
			(stroke
				(width 0.1)
				(type default)
			)
			(layer "B.Fab")
		)
		(fp_line
			(start 0.299974 0.150114)
			(end 0.299974 -0.150114)
			(stroke
				(width 0.1)
				(type default)
			)
			(layer "B.Fab")
		)
		(pad "1" smd rect
			(at 0.2667 0 180)
			(size 0.3048 0.381)
			(layers "B.Cu" "B.Mask" "B.Paste")
			(net "P12V_NIC3")
		)
		(pad "2" smd rect
			(at -0.2667 0 180)
			(size 0.3048 0.381)
			(layers "B.Cu" "B.Mask" "B.Paste")
			(net "GND")
		)
	)
)
